# S9S_MB_2U (Grand Teton) — schematic netlist excerpt (pin names and nets, part order shuffled) for the footprints in the layout excerpt that follows; sources: Cadence DE-HDL packaged netlist, KiCad conversion of 03242023_DA0F0TMBIJ0_F0T_Motherboard_J_brd_V01_OCP.brd

J71  PICOPROBE_BXA  DELTA-L 4.0 EMPTY  pkg TRIANG_LAUNCH_3PXB  page 308
  \1_p\  = DELTA_L_85_5INCH_IN1_DN
  \2_n\  = DELTA_L_85_5INCH_IN1_DP
  \3_g\  = DELTA_L_GND_1

(kicad_pcb
	(version 20260206)
	(generator "pcbnew")
	(generator_version "10.0")
	(general
		(thickness 1.6)
		(legacy_teardrops no)
	)
	(paper "A4")
	(title_block
		(title "03242023_DA0F0TMBIJ0_F0T_Motherboard_J_brd_V01_OCP.brd")
		(comment 1 "Grand Teton / footprints 3740-3740 of 6105")
	)
	(layers
		(0 "F.Cu" signal "TOP")
		(4 "In1.Cu" signal "GND")
		(6 "In2.Cu" signal "IN1")
		(8 "In3.Cu" signal "GND1")
		(10 "In4.Cu" signal "IN2")
		(12 "In5.Cu" signal "GND2")
		(14 "In6.Cu" signal "IN3")
		(16 "In7.Cu" signal "GND3")
		(18 "In8.Cu" signal "VCC")
		(20 "In9.Cu" signal "VCC1")
		(22 "In10.Cu" signal "GND4")
		(24 "In11.Cu" signal "IN4")
		(26 "In12.Cu" signal "GND5")
		(28 "In13.Cu" signal "IN5")
		(30 "In14.Cu" signal "GND6")
		(32 "In15.Cu" signal "IN6")
		(34 "In16.Cu" signal "GND7")
		(2 "B.Cu" signal "BOTTOM")
		(9 "F.Adhes" user "F.Adhesive")
		(11 "B.Adhes" user "B.Adhesive")
		(13 "F.Paste" user "Package Geometry/Pastemask Top")
		(15 "B.Paste" user "Package Geometry/Pastemask Bottom")
		(5 "F.SilkS" user "Ref Des/Silkscreen Top")
		(7 "B.SilkS" user "Ref Des/Silkscreen Bottom")
		(1 "F.Mask" user "Board Geometry/Soldermask Top")
		(3 "B.Mask" user "Board Geometry/Soldermask Bottom")
		(17 "Dwgs.User" user "User.Drawings")
		(19 "Cmts.User" user "User.Comments")
		(21 "Eco1.User" user "User.Eco1")
		(23 "Eco2.User" user "User.Eco2")
		(25 "Edge.Cuts" user "Board Geometry/Outline")
		(27 "Margin" user)
		(31 "F.CrtYd" user "Package Geometry/Place Bound Top")
		(29 "B.CrtYd" user "Package Geometry/Place Bound Bottom")
		(35 "F.Fab" user "Ref Des/Assembly Top")
		(33 "B.Fab" user "Ref Des/Assembly Bottom")
	)
	(footprint ""
		(layer "F.Cu")
		(at 339.298534 0.383794)
		(property "Reference" "J71"
			(at -4.245864 1.013206 90)
			(unlocked yes)
			(layer "F.SilkS")
			(effects
				(font
					(size 0.7874 0.5842)
					(thickness 0.1524)
				)
				(justify left)
			)
		)
		(property "Value" ""
			(at 0 0 0)
			(layer "F.Fab")
			(effects
				(font
					(size 1.27 1.27)
				)
			)
		)
		(duplicate_pad_numbers_are_jumpers no)
		(fp_line
			(start -1.2192 -2.1082)
			(end 1.2192 -2.1082)
			(stroke
				(width 0.1524)
				(type default)
			)
			(layer "F.SilkS")
		)
		(fp_line
			(start -1.2192 2.1082)
			(end -1.2192 -2.1082)
			(stroke
				(width 0.1524)
				(type default)
			)
			(layer "F.SilkS")
		)
		(fp_line
			(start 1.2192 -2.1082)
			(end 1.2192 2.1082)
			(stroke
				(width 0.1524)
				(type default)
			)
			(layer "F.SilkS")
		)
		(fp_line
			(start 1.2192 2.1082)
			(end -1.2192 2.1082)
			(stroke
				(width 0.1524)
				(type default)
			)
			(layer "F.SilkS")
		)
		(pad "" np_thru_hole circle
			(at -2.8829 -1.27 270)
			(size 1.0414 1.0414)
			(drill 1.0414)
			(layers "*.Cu" "*.Mask")
			(clearance 0.381)
			(thermal_gap 0.381)
		)
		(pad "" np_thru_hole circle
			(at -2.8829 1.27 270)
			(size 1.0414 1.0414)
			(drill 1.0414)
			(layers "*.Cu" "*.Mask")
			(clearance 0.381)
			(thermal_gap 0.381)
		)
		(pad "" np_thru_hole circle
			(at 3.4671 -1.27 270)
			(size 1.0414 1.0414)
			(drill 1.0414)
			(layers "*.Cu" "*.Mask")
			(clearance 0.381)
			(thermal_gap 0.381)
		)
		(pad "" np_thru_hole circle
			(at 3.4671 1.27 270)
			(size 1.0414 1.0414)
			(drill 1.0414)
			(layers "*.Cu" "*.Mask")
			(clearance 0.381)
			(thermal_gap 0.381)
		)
		(pad "1" smd rect
			(at 0.8255 -0.249936 270)
			(size 0.3048 0.508)
			(layers "F.Cu" "F.Mask" "F.Paste")
			(net "DELTA_L_85_5INCH_IN1_DN")
		)
		(pad "2" smd rect
			(at 0.8255 0.249936 270)
			(size 0.3048 0.508)
			(layers "F.Cu" "F.Mask" "F.Paste")
			(net "DELTA_L_85_5INCH_IN1_DP")
		)
		(pad "3" smd circle
			(at 0 0)
			(size 0 0)
			(layers "F.Cu" "F.Mask" "F.Paste")
			(net "DELTA_L_GND_1")
		)
		(zone
			(layer "F.Cu")
			(hatch none 0.5)
			(connect_pads
				(clearance 0)
			)
			(min_thickness 0.25)
			(keepout
				(tracks not_allowed)
				(vias allowed)
				(pads allowed)
				(copperpour not_allowed)
				(footprints allowed)
			)
			(placement
				(enabled no)
				(sheetname "")
			)
			(fill
				(thermal_gap 0.5)
				(thermal_bridge_width 0.5)
				(island_removal_mode 0)
			)
			(polygon
				(pts
					(xy 340.416134 -0.164846) (xy 340.416134 -0.069342) (xy 339.819234 -0.069342) (xy 339.819234 0.337058)
					(xy 340.416134 0.337058) (xy 340.416134 0.43053) (xy 339.819234 0.43053) (xy 339.819234 0.83693)
					(xy 340.416134 0.83693) (xy 340.416134 0.932434) (xy 339.717634 0.932434) (xy 339.717634 -0.164846)
				)
			)
		)
		(zone
			(layers "F.Cu" "B.Cu" "In1.Cu" "In2.Cu" "In3.Cu" "In4.Cu" "In5.Cu" "In6.Cu"
				"In7.Cu" "In8.Cu" "In9.Cu" "In10.Cu" "In11.Cu" "In12.Cu" "In13.Cu" "In14.Cu"
				"In15.Cu" "In16.Cu"
			)
			(hatch none 0.5)
			(connect_pads
				(clearance 0)
			)
			(min_thickness 0.25)
			(keepout
				(tracks not_allowed)
				(vias allowed)
				(pads allowed)
				(copperpour not_allowed)
				(footprints allowed)
			)
			(placement
				(enabled no)
				(sheetname "")
			)
			(fill
				(thermal_gap 0.5)
				(thermal_bridge_width 0.5)
				(island_removal_mode 0)
			)
			(polygon
				(pts
					(arc
						(start 337.342734 -0.886206)
						(mid 335.488534 -0.886206)
						(end 337.342734 -0.886206)
					)
				)
			)
		)
		(zone
			(layers "F.Cu" "B.Cu" "In1.Cu" "In2.Cu" "In3.Cu" "In4.Cu" "In5.Cu" "In6.Cu"
				"In7.Cu" "In8.Cu" "In9.Cu" "In10.Cu" "In11.Cu" "In12.Cu" "In13.Cu" "In14.Cu"
				"In15.Cu" "In16.Cu"
			)
			(hatch none 0.5)
			(connect_pads
				(clearance 0)
			)
			(min_thickness 0.25)
			(keepout
				(tracks not_allowed)
				(vias allowed)
				(pads allowed)
				(copperpour not_allowed)
				(footprints allowed)
			)
			(placement
				(enabled no)
				(sheetname "")
			)
			(fill
				(thermal_gap 0.5)
				(thermal_bridge_width 0.5)
				(island_removal_mode 0)
			)
			(polygon
				(pts
					(arc
						(start 337.342734 1.653794)
						(mid 335.488534 1.653794)
						(end 337.342734 1.653794)
					)
				)
			)
		)
		(zone
			(layers "F.Cu" "B.Cu" "In1.Cu" "In2.Cu" "In3.Cu" "In4.Cu" "In5.Cu" "In6.Cu"
				"In7.Cu" "In8.Cu" "In9.Cu" "In10.Cu" "In11.Cu" "In12.Cu" "In13.Cu" "In14.Cu"
				"In15.Cu" "In16.Cu"
			)
			(hatch none 0.5)
			(connect_pads
				(clearance 0)
			)
			(min_thickness 0.25)
			(keepout
				(tracks not_allowed)
				(vias allowed)
				(pads allowed)
				(copperpour not_allowed)
				(footprints allowed)
			)
			(placement
				(enabled no)
				(sheetname "")
			)
			(fill
				(thermal_gap 0.5)
				(thermal_bridge_width 0.5)
				(island_removal_mode 0)
			)
			(polygon
				(pts
					(arc
						(start 343.692734 -0.886206)
						(mid 341.838534 -0.886206)
						(end 343.692734 -0.886206)
					)
				)
			)
		)
		(zone
			(layers "F.Cu" "B.Cu" "In1.Cu" "In2.Cu" "In3.Cu" "In4.Cu" "In5.Cu" "In6.Cu"
				"In7.Cu" "In8.Cu" "In9.Cu" "In10.Cu" "In11.Cu" "In12.Cu" "In13.Cu" "In14.Cu"
				"In15.Cu" "In16.Cu"
			)
			(hatch none 0.5)
			(connect_pads
				(clearance 0)
			)
			(min_thickness 0.25)
			(keepout
				(tracks not_allowed)
				(vias allowed)
				(pads allowed)
				(copperpour not_allowed)
				(footprints allowed)
			)
			(placement
				(enabled no)
				(sheetname "")
			)
			(fill
				(thermal_gap 0.5)
				(thermal_bridge_width 0.5)
				(island_removal_mode 0)
			)
			(polygon
				(pts
					(arc
						(start 343.692734 1.653794)
						(mid 341.838534 1.653794)
						(end 343.692734 1.653794)
					)
				)
			)
		)
	)
)
